(kicad_pcb
	(version 20241229)
	(generator "pcbnew")
	(generator_version "9.0")
	(general
		(thickness 1.552)
		(legacy_teardrops no)
	)
	(paper "A4")
	(title_block
		(date "2023-07-25")
		(rev "1.1.4")
		(comment 9 "footprints 281-286 of 379")
	)
	(layers
		(0 "F.Cu" signal)
		(4 "In1.Cu" signal)
		(6 "In2.Cu" signal)
		(8 "In3.Cu" signal)
		(10 "In4.Cu" signal)
		(12 "In5.Cu" signal)
		(14 "In6.Cu" signal)
		(2 "B.Cu" signal)
		(9 "F.Adhes" user "F.Adhesive")
		(11 "B.Adhes" user "B.Adhesive")
		(13 "F.Paste" user)
		(15 "B.Paste" user)
		(5 "F.SilkS" user "F.Silkscreen")
		(7 "B.SilkS" user "B.Silkscreen")
		(1 "F.Mask" user)
		(3 "B.Mask" user)
		(17 "Dwgs.User" user "User.Drawings")
		(19 "Cmts.User" user "User.Comments")
		(21 "Eco1.User" user "User.Eco1")
		(23 "Eco2.User" user "User.Eco2")
		(25 "Edge.Cuts" user)
		(27 "Margin" user)
		(31 "F.CrtYd" user "F.Courtyard")
		(29 "B.CrtYd" user "B.Courtyard")
		(35 "F.Fab" user)
		(33 "B.Fab" user)
	)
	(footprint "antmicro-footprints:C_0201"
		(layer "B.Cu")
		(at 126.7 91.01)
		(descr "Capacitor SMD 0201")
		(tags "capacitor SMD 0201")
		(property "Reference" "C98"
			(at -10.47 -12.205736 0)
			(layer "B.SilkS")
			(effects
				(font
					(size 0.65 0.65)
					(thickness 0.15)
				)
				(justify right bottom mirror)
			)
		)
		(property "Value" "C_100n_0201"
			(at 0 -1.4 0)
			(layer "B.Fab")
			(hide yes)
			(effects
				(font
					(size 0.7 0.7)
					(thickness 0.15)
				)
				(justify right bottom mirror)
			)
		)
		(property "Datasheet" "https://www.yageo.com/en/Chart/Download/pdf/CC0201KRX6S5BB104"
			(at 0 0 0)
			(layer "F.Fab")
			(hide yes)
			(effects
				(font
					(size 1.27 1.27)
					(thickness 0.15)
				)
			)
		)
		(property "Description" "SMD Multilayer Ceramic Capacitor, 0.1 µF, 6.3 V, 0201 [0603 Metric], ± 10%, X6S, CC Series"
			(at 0 0 0)
			(layer "F.Fab")
			(hide yes)
			(effects
				(font
					(size 1.27 1.27)
					(thickness 0.15)
				)
			)
		)
		(property "Author" "Antmicro"
			(at 0 0 0)
			(layer "B.Fab")
			(hide yes)
			(effects
				(font
					(size 1 1)
					(thickness 0.15)
				)
				(justify mirror)
			)
		)
		(property "Dielectric" ""
			(at 0 0 0)
			(layer "B.Fab")
			(hide yes)
			(effects
				(font
					(size 1 1)
					(thickness 0.15)
				)
				(justify mirror)
			)
		)
		(property "License" "Apache-2.0"
			(at 0 0 0)
			(layer "B.Fab")
			(hide yes)
			(effects
				(font
					(size 1 1)
					(thickness 0.15)
				)
				(justify mirror)
			)
		)
		(property "MPN" "CC0201KRX6S5BB104"
			(at 0 0 0)
			(layer "B.Fab")
			(hide yes)
			(effects
				(font
					(size 1 1)
					(thickness 0.15)
				)
				(justify mirror)
			)
		)
		(property "Manufacturer" "YAGEO"
			(at 0 0 0)
			(layer "B.Fab")
			(hide yes)
			(effects
				(font
					(size 1 1)
					(thickness 0.15)
				)
				(justify mirror)
			)
		)
		(property "Val" "100n"
			(at 0 0 0)
			(layer "B.Fab")
			(hide yes)
			(effects
				(font
					(size 1 1)
					(thickness 0.15)
				)
				(justify mirror)
			)
		)
		(property "Voltage" ""
			(at 0 0 0)
			(layer "B.Fab")
			(hide yes)
			(effects
				(font
					(size 1 1)
					(thickness 0.15)
				)
				(justify mirror)
			)
		)
		(property "Public" "False"
			(at 0 0 0)
			(unlocked yes)
			(layer "B.Fab")
			(hide yes)
			(effects
				(font
					(size 1 1)
					(thickness 0.15)
				)
				(justify mirror)
			)
		)
		(sheetname "/FPGA Power/")
		(sheetfile "FPGA_Power.kicad_sch")
		(attr smd)
		(fp_rect
			(start -0.7 0.35)
			(end 0.7 -0.35)
			(stroke
				(width 0.05)
				(type default)
			)
			(fill no)
			(layer "B.CrtYd")
		)
		(fp_rect
			(start 0.3 -0.15)
			(end -0.301 0.149)
			(stroke
				(width 0.15)
				(type solid)
			)
			(fill no)
			(layer "B.Fab")
		)
		(fp_text user "Author: Antmicro"
			(at -0.72 -5.4 180)
			(layer "B.Fab")
			(effects
				(font
					(size 0.7 0.7)
					(thickness 0.15)
				)
				(justify left bottom mirror)
			)
		)
		(fp_text user "License: Apache-2.0"
			(at -0.72 -4.4 180)
			(layer "B.Fab")
			(effects
				(font
					(size 0.7 0.7)
					(thickness 0.15)
				)
				(justify left bottom mirror)
			)
		)
		(fp_text user "${REFERENCE}"
			(at -0.72 -3.4 180)
			(layer "B.Fab")
			(effects
				(font
					(size 0.7 0.7)
					(thickness 0.15)
				)
				(justify left bottom mirror)
			)
		)
		(pad "" smd roundrect
			(at -0.349 0.002)
			(size 0.318 0.36)
			(layers "B.Paste")
			(roundrect_rratio 0.25)
		)
		(pad "" smd roundrect
			(at 0.341 0.002)
			(size 0.318 0.36)
			(layers "B.Paste")
			(roundrect_rratio 0.25)
		)
		(pad "1" smd roundrect
			(at -0.321 0.002)
			(size 0.46 0.4)
			(layers "B.Cu" "B.Mask")
			(roundrect_rratio 0.25)
			(net 1 "GND")
			(pintype "passive")
		)
		(pad "2" smd roundrect
			(at 0.32 0.002)
			(size 0.46 0.4)
			(layers "B.Cu" "B.Mask")
			(roundrect_rratio 0.25)
			(net 4 "1V0_Power")
			(pintype "passive")
		)
	)
	(footprint "antmicro-footprints:TP_SMD_0.75mm"
		(layer "B.Cu")
		(at 90.94 88.2 90)
		(property "Reference" "TP39"
			(at 0.76 0.39 90)
			(layer "B.SilkS")
			(effects
				(font
					(size 0.65 0.65)
					(thickness 0.15)
				)
				(justify right bottom mirror)
			)
		)
		(property "Value" "TP_0.75mm_SMD"
			(at 0 -1.2 90)
			(layer "B.Fab")
			(hide yes)
			(effects
				(font
					(size 0.7 0.7)
					(thickness 0.15)
				)
				(justify right bottom mirror)
			)
		)
		(property "Description" "SMT test point"
			(at 0 0 90)
			(layer "F.Fab")
			(hide yes)
			(effects
				(font
					(size 1.27 1.27)
					(thickness 0.15)
				)
			)
		)
		(property "Author" "Antmicro"
			(at 179.14 -2.74 0)
			(layer "B.Fab")
			(hide yes)
			(effects
				(font
					(size 1 1)
					(thickness 0.15)
				)
				(justify mirror)
			)
		)
		(property "License" "Apache-2.0"
			(at 179.14 -2.74 0)
			(layer "B.Fab")
			(hide yes)
			(effects
				(font
					(size 1 1)
					(thickness 0.15)
				)
				(justify mirror)
			)
		)
		(property "MPN" ""
			(at 179.14 -2.74 0)
			(layer "B.Fab")
			(hide yes)
			(effects
				(font
					(size 1 1)
					(thickness 0.15)
				)
				(justify mirror)
			)
		)
		(property "Manufacturer" ""
			(at 179.14 -2.74 0)
			(layer "B.Fab")
			(hide yes)
			(effects
				(font
					(size 1 1)
					(thickness 0.15)
				)
				(justify mirror)
			)
		)
		(sheetname "/SDI/")
		(sheetfile "sdi.kicad_sch")
		(attr exclude_from_pos_files)
		(fp_circle
			(center 0 0)
			(end 0.475 0)
			(stroke
				(width 0.05)
				(type default)
			)
			(fill no)
			(layer "B.CrtYd")
		)
		(fp_text user "${REFERENCE}"
			(at -0.4 -2.7 270)
			(layer "B.Fab")
			(effects
				(font
					(size 0.7 0.7)
					(thickness 0.15)
				)
				(justify left bottom mirror)
			)
		)
		(fp_text user "License: Apache-2.0"
			(at -0.4 -5.101 270)
			(layer "B.Fab")
			(effects
				(font
					(size 0.7 0.7)
					(thickness 0.15)
				)
				(justify left bottom mirror)
			)
		)
		(fp_text user "Author: Antmicro"
			(at -0.4 -3.901 270)
			(layer "B.Fab")
			(effects
				(font
					(size 0.7 0.7)
					(thickness 0.15)
				)
				(justify left bottom mirror)
			)
		)
		(pad "1" smd circle
			(at 0 0 90)
			(size 0.75 0.75)
			(layers "B.Cu" "B.Mask")
			(net 185 "/SDI/SDO_EN{slash}DIS")
			(pinfunction "1")
			(pintype "passive")
		)
	)
	(footprint "antmicro-footprints:R_0402_1005Metric"
		(layer "B.Cu")
		(at 105.89 91.8 90)
		(descr "Resistor SMD 0402")
		(tags "resistor SMD 0402")
		(property "Reference" "R90"
			(at -1.04 0.34 270)
			(layer "B.SilkS")
			(effects
				(font
					(size 0.65 0.65)
					(thickness 0.15)
				)
				(justify left bottom mirror)
			)
		)
		(property "Value" "R_4k7_0402"
			(at 0 -1.4 270)
			(layer "B.Fab")
			(hide yes)
			(effects
				(font
					(size 0.7 0.7)
					(thickness 0.15)
				)
				(justify left bottom mirror)
			)
		)
		(property "Datasheet" "https://www.bourns.com/docs/product-datasheets/cr.pdf"
			(at 0 0 90)
			(layer "F.Fab")
			(hide yes)
			(effects
				(font
					(size 1.27 1.27)
					(thickness 0.15)
				)
			)
		)
		(property "Description" "SMD Chip Resistor, 4.7 kohm, ± 1%, 62.5 mW, 0402 [1005 Metric], Thick Film, General Purpose"
			(at 0 0 90)
			(layer "F.Fab")
			(hide yes)
			(effects
				(font
					(size 1.27 1.27)
					(thickness 0.15)
				)
			)
		)
		(property "Author" "Antmicro"
			(at 197.69 -14.09 0)
			(layer "B.Fab")
			(hide yes)
			(effects
				(font
					(size 1 1)
					(thickness 0.15)
				)
				(justify mirror)
			)
		)
		(property "License" "Apache-2.0"
			(at 197.69 -14.09 0)
			(layer "B.Fab")
			(hide yes)
			(effects
				(font
					(size 1 1)
					(thickness 0.15)
				)
				(justify mirror)
			)
		)
		(property "MPN" "CR0402-FX-4701GLF"
			(at 197.69 -14.09 0)
			(layer "B.Fab")
			(hide yes)
			(effects
				(font
					(size 1 1)
					(thickness 0.15)
				)
				(justify mirror)
			)
		)
		(property "Manufacturer" "Bourns"
			(at 197.69 -14.09 0)
			(layer "B.Fab")
			(hide yes)
			(effects
				(font
					(size 1 1)
					(thickness 0.15)
				)
				(justify mirror)
			)
		)
		(property "Tolerance" "1%"
			(at 197.69 -14.09 0)
			(layer "B.Fab")
			(hide yes)
			(effects
				(font
					(size 1 1)
					(thickness 0.15)
				)
				(justify mirror)
			)
		)
		(property "Val" "4k7"
			(at 197.69 -14.09 0)
			(layer "B.Fab")
			(hide yes)
			(effects
				(font
					(size 1 1)
					(thickness 0.15)
				)
				(justify mirror)
			)
		)
		(sheetname "/FPGA/")
		(sheetfile "fpga.kicad_sch")
		(attr smd)
		(fp_rect
			(start -0.925 0.47)
			(end 0.925 -0.47)
			(stroke
				(width 0.05)
				(type default)
			)
			(fill no)
			(layer "B.CrtYd")
		)
		(fp_rect
			(start -0.5 0.25)
			(end 0.5 -0.25)
			(stroke
				(width 0.15)
				(type solid)
			)
			(fill no)
			(layer "B.Fab")
		)
		(fp_text user "${REFERENCE}"
			(at -0.95 -3.168 270)
			(layer "B.Fab")
			(effects
				(font
					(size 0.7 0.7)
					(thickness 0.15)
				)
				(justify left bottom mirror)
			)
		)
		(fp_text user "Author: Antmicro"
			(at -0.95 -4.169 270)
			(layer "B.Fab")
			(effects
				(font
					(size 0.7 0.7)
					(thickness 0.15)
				)
				(justify left bottom mirror)
			)
		)
		(fp_text user "License: Apache-2.0"
			(at -0.95 -5.169 270)
			(layer "B.Fab")
			(effects
				(font
					(size 0.7 0.7)
					(thickness 0.15)
				)
				(justify left bottom mirror)
			)
		)
		(pad "1" smd roundrect
			(at -0.48 0 90)
			(size 0.59 0.64)
			(layers "B.Cu" "B.Mask" "B.Paste")
			(roundrect_rratio 0.25)
			(net 306 "Net-(U18-~{CS})")
			(pintype "passive")
		)
		(pad "2" smd roundrect
			(at 0.48 0 90)
			(size 0.59 0.64)
			(layers "B.Cu" "B.Mask" "B.Paste")
			(roundrect_rratio 0.25)
			(net 2 "+3V3")
			(pintype "passive")
		)
	)
	(footprint "antmicro-footprints:R_0402_1005Metric"
		(layer "B.Cu")
		(at 161.69 73.9)
		(descr "Resistor SMD 0402")
		(tags "resistor SMD 0402")
		(property "Reference" "R63"
			(at -0.96 0.84 180)
			(layer "B.SilkS")
			(effects
				(font
					(size 0.65 0.65)
					(thickness 0.15)
				)
				(justify left bottom mirror)
			)
		)
		(property "Value" "R_10k_0402"
			(at 0 -1.4 180)
			(layer "B.Fab")
			(hide yes)
			(effects
				(font
					(size 0.7 0.7)
					(thickness 0.15)
				)
				(justify left bottom mirror)
			)
		)
		(property "Datasheet" "https://www.bourns.com/docs/product-datasheets/cr.pdf"
			(at 0 0 0)
			(layer "F.Fab")
			(hide yes)
			(effects
				(font
					(size 1.27 1.27)
					(thickness 0.15)
				)
			)
		)
		(property "Description" "SMD Chip Resistor, 10 kohm, ± 1%, 62.5 mW, 0402 [1005 Metric], Thick Film, General Purpose"
			(at 0 0 0)
			(layer "F.Fab")
			(hide yes)
			(effects
				(font
					(size 1.27 1.27)
					(thickness 0.15)
				)
			)
		)
		(property "Author" "Antmicro"
			(at 0 0 0)
			(layer "B.Fab")
			(hide yes)
			(effects
				(font
					(size 1 1)
					(thickness 0.15)
				)
				(justify mirror)
			)
		)
		(property "License" "Apache-2.0"
			(at 0 0 0)
			(layer "B.Fab")
			(hide yes)
			(effects
				(font
					(size 1 1)
					(thickness 0.15)
				)
				(justify mirror)
			)
		)
		(property "MPN" "CR0402-FX-1002GLF"
			(at 0 0 0)
			(layer "B.Fab")
			(hide yes)
			(effects
				(font
					(size 1 1)
					(thickness 0.15)
				)
				(justify mirror)
			)
		)
		(property "Manufacturer" "Bourns"
			(at 0 0 0)
			(layer "B.Fab")
			(hide yes)
			(effects
				(font
					(size 1 1)
					(thickness 0.15)
				)
				(justify mirror)
			)
		)
		(property "Tolerance" "1%"
			(at 0 0 0)
			(layer "B.Fab")
			(hide yes)
			(effects
				(font
					(size 1 1)
					(thickness 0.15)
				)
				(justify mirror)
			)
		)
		(property "Val" "10k"
			(at 0 0 0)
			(layer "B.Fab")
			(hide yes)
			(effects
				(font
					(size 1 1)
					(thickness 0.15)
				)
				(justify mirror)
			)
		)
		(sheetname "/Power Supply/")
		(sheetfile "supply.kicad_sch")
		(attr smd)
		(fp_rect
			(start -0.925 0.47)
			(end 0.925 -0.47)
			(stroke
				(width 0.05)
				(type default)
			)
			(fill no)
			(layer "B.CrtYd")
		)
		(fp_rect
			(start -0.5 0.25)
			(end 0.5 -0.25)
			(stroke
				(width 0.15)
				(type solid)
			)
			(fill no)
			(layer "B.Fab")
		)
		(fp_text user "${REFERENCE}"
			(at -0.95 -3.168 180)
			(layer "B.Fab")
			(effects
				(font
					(size 0.7 0.7)
					(thickness 0.15)
				)
				(justify left bottom mirror)
			)
		)
		(fp_text user "Author: Antmicro"
			(at -0.95 -4.169 180)
			(layer "B.Fab")
			(effects
				(font
					(size 0.7 0.7)
					(thickness 0.15)
				)
				(justify left bottom mirror)
			)
		)
		(fp_text user "License: Apache-2.0"
			(at -0.95 -5.169 180)
			(layer "B.Fab")
			(effects
				(font
					(size 0.7 0.7)
					(thickness 0.15)
				)
				(justify left bottom mirror)
			)
		)
		(pad "1" smd roundrect
			(at -0.48 0)
			(size 0.59 0.64)
			(layers "B.Cu" "B.Mask" "B.Paste")
			(roundrect_rratio 0.25)
			(net 259 "Net-(Q1-D)")
			(pintype "passive")
		)
		(pad "2" smd roundrect
			(at 0.48 0)
			(size 0.59 0.64)
			(layers "B.Cu" "B.Mask" "B.Paste")
			(roundrect_rratio 0.25)
			(net 329 "/Power Supply/FFC2_5V_1")
			(pintype "passive")
		)
	)
	(footprint "antmicro-footprints:C_0402_1005Metric"
		(layer "B.Cu")
		(at 120.93 62.4)
		(descr "Capacitor SMD 0402")
		(tags "capacitor SMD 0402")
		(property "Reference" "C50"
			(at -4.9 0.34 0)
			(layer "B.SilkS")
			(effects
				(font
					(size 0.65 0.65)
					(thickness 0.15)
				)
				(justify right bottom mirror)
			)
		)
		(property "Value" "C_100n_0402"
			(at 0 -1.4 0)
			(layer "B.Fab")
			(hide yes)
			(effects
				(font
					(size 0.7 0.7)
					(thickness 0.15)
				)
				(justify right bottom mirror)
			)
		)
		(property "Datasheet" "https://www.murata.com/products/productdetail?partno=GRM155R61H104KE14%23"
			(at 0 0 0)
			(layer "F.Fab")
			(hide yes)
			(effects
				(font
					(size 1.27 1.27)
					(thickness 0.15)
				)
			)
		)
		(property "Description" "SMD Multilayer Ceramic Capacitor, 0.1 µF, 50 V, 0402 [1005 Metric], ± 10%, X5R, GRM Series"
			(at 0 0 0)
			(layer "F.Fab")
			(hide yes)
			(effects
				(font
					(size 1.27 1.27)
					(thickness 0.15)
				)
			)
		)
		(property "Author" "Antmicro"
			(at 0 0 0)
			(layer "B.Fab")
			(hide yes)
			(effects
				(font
					(size 1 1)
					(thickness 0.15)
				)
				(justify mirror)
			)
		)
		(property "Dielectric" "X5R"
			(at 0 0 0)
			(layer "B.Fab")
			(hide yes)
			(effects
				(font
					(size 1 1)
					(thickness 0.15)
				)
				(justify mirror)
			)
		)
		(property "License" "Apache-2.0"
			(at 0 0 0)
			(layer "B.Fab")
			(hide yes)
			(effects
				(font
					(size 1 1)
					(thickness 0.15)
				)
				(justify mirror)
			)
		)
		(property "MPN" "GRM155R61H104KE14D"
			(at 0 0 0)
			(layer "B.Fab")
			(hide yes)
			(effects
				(font
					(size 1 1)
					(thickness 0.15)
				)
				(justify mirror)
			)
		)
		(property "Manufacturer" "Murata"
			(at 0 0 0)
			(layer "B.Fab")
			(hide yes)
			(effects
				(font
					(size 1 1)
					(thickness 0.15)
				)
				(justify mirror)
			)
		)
		(property "Val" "100n"
			(at 0 0 0)
			(layer "B.Fab")
			(hide yes)
			(effects
				(font
					(size 1 1)
					(thickness 0.15)
				)
				(justify mirror)
			)
		)
		(property "Voltage" "50V"
			(at 0 0 0)
			(layer "B.Fab")
			(hide yes)
			(effects
				(font
					(size 1 1)
					(thickness 0.15)
				)
				(justify mirror)
			)
		)
		(sheetname "/DDR3/")
		(sheetfile "ddr3.kicad_sch")
		(attr smd)
		(fp_rect
			(start -0.925 0.47)
			(end 0.925 -0.47)
			(stroke
				(width 0.05)
				(type default)
			)
			(fill no)
			(layer "B.CrtYd")
		)
		(fp_line
			(start -0.494 -0.248)
			(end -0.494 0.25)
			(stroke
				(width 0.15)
				(type solid)
			)
			(layer "B.Fab")
		)
		(fp_line
			(start -0.494 0.25)
			(end 0.504 0.25)
			(stroke
				(width 0.15)
				(type solid)
			)
			(layer "B.Fab")
		)
		(fp_line
			(start 0.504 -0.248)
			(end -0.494 -0.248)
			(stroke
				(width 0.15)
				(type solid)
			)
			(layer "B.Fab")
		)
		(fp_line
			(start 0.504 0.25)
			(end 0.504 -0.248)
			(stroke
				(width 0.15)
				(type solid)
			)
			(layer "B.Fab")
		)
		(fp_text user "Author: Antmicro"
			(at -0.939 -3.399 180)
			(layer "B.Fab")
			(effects
				(font
					(size 0.7 0.7)
					(thickness 0.15)
				)
				(justify left bottom mirror)
			)
		)
		(fp_text user "${REFERENCE}"
			(at -0.939 -4.599 180)
			(layer "B.Fab")
			(effects
				(font
					(size 0.7 0.7)
					(thickness 0.15)
				)
				(justify left bottom mirror)
			)
		)
		(fp_text user "License: Apache-2.0"
			(at -0.939 -5.799 180)
			(layer "B.Fab")
			(effects
				(font
					(size 0.7 0.7)
					(thickness 0.15)
				)
				(justify left bottom mirror)
			)
		)
		(pad "1" smd roundrect
			(at -0.48 0)
			(size 0.59 0.64)
			(layers "B.Cu" "B.Mask" "B.Paste")
			(roundrect_rratio 0.25)
			(net 1 "GND")
			(pintype "passive")
		)
		(pad "2" smd roundrect
			(at 0.48 0)
			(size 0.59 0.64)
			(layers "B.Cu" "B.Mask" "B.Paste")
			(roundrect_rratio 0.25)
			(net 5 "Vref")
			(pintype "passive")
		)
	)
	(footprint "antmicro-footprints:TP_SMD_0.75mm"
		(layer "B.Cu")
		(at 94.69 88.95 90)
		(property "Reference" "TP36"
			(at -2.99 0.34 90)
			(layer "B.SilkS")
			(effects
				(font
					(size 0.65 0.65)
					(thickness 0.15)
				)
				(justify right bottom mirror)
			)
		)
		(property "Value" "TP_0.75mm_SMD"
			(at 0 -1.2 90)
			(layer "B.Fab")
			(hide yes)
			(effects
				(font
					(size 0.7 0.7)
					(thickness 0.15)
				)
				(justify right bottom mirror)
			)
		)
		(property "Description" "SMT test point"
			(at 0 0 90)
			(layer "F.Fab")
			(hide yes)
			(effects
				(font
					(size 1.27 1.27)
					(thickness 0.15)
				)
			)
		)
		(property "Author" "Antmicro"
			(at 183.64 -5.74 0)
			(layer "B.Fab")
			(hide yes)
			(effects
				(font
					(size 1 1)
					(thickness 0.15)
				)
				(justify mirror)
			)
		)
		(property "License" "Apache-2.0"
			(at 183.64 -5.74 0)
			(layer "B.Fab")
			(hide yes)
			(effects
				(font
					(size 1 1)
					(thickness 0.15)
				)
				(justify mirror)
			)
		)
		(property "MPN" ""
			(at 183.64 -5.74 0)
			(layer "B.Fab")
			(hide yes)
			(effects
				(font
					(size 1 1)
					(thickness 0.15)
				)
				(justify mirror)
			)
		)
		(property "Manufacturer" ""
			(at 183.64 -5.74 0)
			(layer "B.Fab")
			(hide yes)
			(effects
				(font
					(size 1 1)
					(thickness 0.15)
				)
				(justify mirror)
			)
		)
		(sheetname "/SDI/")
		(sheetfile "sdi.kicad_sch")
		(attr exclude_from_pos_files)
		(fp_circle
			(center 0 0)
			(end 0.475 0)
			(stroke
				(width 0.05)
				(type default)
			)
			(fill no)
			(layer "B.CrtYd")
		)
		(fp_text user "${REFERENCE}"
			(at -0.4 -2.7 270)
			(layer "B.Fab")
			(effects
				(font
					(size 0.7 0.7)
					(thickness 0.15)
				)
				(justify left bottom mirror)
			)
		)
		(fp_text user "Author: Antmicro"
			(at -0.4 -3.901 270)
			(layer "B.Fab")
			(effects
				(font
					(size 0.7 0.7)
					(thickness 0.15)
				)
				(justify left bottom mirror)
			)
		)
		(fp_text user "License: Apache-2.0"
			(at -0.4 -5.101 270)
			(layer "B.Fab")
			(effects
				(font
					(size 0.7 0.7)
					(thickness 0.15)
				)
				(justify left bottom mirror)
			)
		)
		(pad "1" smd circle
			(at 0 0 90)
			(size 0.75 0.75)
			(layers "B.Cu" "B.Mask")
			(net 175 "/SDI/RESET_TRST")
			(pinfunction "1")
			(pintype "passive")
		)
	)
)
